# T6G (Grand Teton) — schematic netlist excerpt (pin names and nets, part order shuffled) for the footprints in the layout excerpt that follows; sources: Cadence DE-HDL packaged netlist, KiCad conversion of 04192023_DAF0TMB3IC0_F0TG_MB_C_brd_V02_OCP.brd

PC144_IOP0_2  Q_CAP  2.2UF 10V 10% X6S  pkg C0402  page 205 : A = PVDDCR_CPU1_P0_PVCC ; B = GND
C7032  Q_CAPP  470UF 2.5V 20% SPCAP  pkg SMLF  page 279 : A = P0V9_CPU0_RT_2D ; B = GND
C758  Q_CAP_DIFFBUS  DIFF BUS_0.22UF 6.3V 20% X6S  pkg C0201  page 66 : \1\ = P5E_CPU1_P2_TX_C_DN<7> ; \2\ = P5E_CPU1_P2_TX_DN<7>

(kicad_pcb
	(version 20260206)
	(generator "pcbnew")
	(generator_version "10.0")
	(general
		(thickness 1.6)
		(legacy_teardrops no)
	)
	(paper "A4")
	(title_block
		(title "04192023_DAF0TMB3IC0_F0TG_MB_C_brd_V02_OCP.brd")
		(comment 1 "Grand Teton / footprints 311-313 of 8354")
	)
	(layers
		(0 "F.Cu" signal "TOP")
		(4 "In1.Cu" signal "GND")
		(6 "In2.Cu" signal "IN1")
		(8 "In3.Cu" signal "GND1")
		(10 "In4.Cu" signal "IN2")
		(12 "In5.Cu" signal "GND2")
		(14 "In6.Cu" signal "IN3")
		(16 "In7.Cu" signal "GND3")
		(18 "In8.Cu" signal "VCC")
		(20 "In9.Cu" signal "VCC1")
		(22 "In10.Cu" signal "GND4")
		(24 "In11.Cu" signal "IN4")
		(26 "In12.Cu" signal "GND5")
		(28 "In13.Cu" signal "IN5")
		(30 "In14.Cu" signal "GND6")
		(32 "In15.Cu" signal "IN6")
		(34 "In16.Cu" signal "GND7")
		(2 "B.Cu" signal "BOTTOM")
		(9 "F.Adhes" user "F.Adhesive")
		(11 "B.Adhes" user "B.Adhesive")
		(13 "F.Paste" user "Package Geometry/Pastemask Top")
		(15 "B.Paste" user "Package Geometry/Pastemask Bottom")
		(5 "F.SilkS" user "Ref Des/Silkscreen Top")
		(7 "B.SilkS" user "Ref Des/Silkscreen Bottom")
		(1 "F.Mask" user "Board Geometry/Soldermask Top")
		(3 "B.Mask" user "Board Geometry/Soldermask Bottom")
		(17 "Dwgs.User" user "User.Drawings")
		(19 "Cmts.User" user "User.Comments")
		(21 "Eco1.User" user "User.Eco1")
		(23 "Eco2.User" user "User.Eco2")
		(25 "Edge.Cuts" user "Board Geometry/Outline")
		(27 "Margin" user)
		(31 "F.CrtYd" user "Package Geometry/Place Bound Top")
		(29 "B.CrtYd" user "Package Geometry/Place Bound Bottom")
		(35 "F.Fab" user "Ref Des/Assembly Top")
		(33 "B.Fab" user "Ref Des/Assembly Bottom")
	)
	(footprint ""
		(layer "F.Cu")
		(at 155.444444 -375.49963 -90)
		(property "Reference" "C758"
			(at 0 0 270)
			(layer "F.SilkS")
			(hide yes)
			(effects
				(font
					(size 1.27 1.27)
				)
			)
		)
		(property "Value" ""
			(at 0 0 270)
			(layer "F.Fab")
			(effects
				(font
					(size 1.27 1.27)
				)
			)
		)
		(duplicate_pad_numbers_are_jumpers no)
		(fp_line
			(start -0.299974 0.150114)
			(end -0.299974 -0.150114)
			(stroke
				(width 0.1)
				(type default)
			)
			(layer "F.Fab")
		)
		(fp_line
			(start 0.299974 0.150114)
			(end -0.299974 0.150114)
			(stroke
				(width 0.1)
				(type default)
			)
			(layer "F.Fab")
		)
		(fp_line
			(start -0.299974 -0.150114)
			(end 0.299974 -0.150114)
			(stroke
				(width 0.1)
				(type default)
			)
			(layer "F.Fab")
		)
		(fp_line
			(start 0.299974 -0.150114)
			(end 0.299974 0.150114)
			(stroke
				(width 0.1)
				(type default)
			)
			(layer "F.Fab")
		)
		(pad "1" smd rect
			(at -0.2667 0 270)
			(size 0.3048 0.381)
			(layers "F.Cu" "F.Mask" "F.Paste")
			(net "P5E_CPU1_P2_TX_C_DN<7>")
		)
		(pad "2" smd rect
			(at 0.2667 0 270)
			(size 0.3048 0.381)
			(layers "F.Cu" "F.Mask" "F.Paste")
			(net "P5E_CPU1_P2_TX_DN<7>")
		)
	)
	(footprint ""
		(layer "F.Cu")
		(at 288.325306 -346.714572 -90)
		(property "Reference" "PC144_IOP0_2"
			(at 0 0 270)
			(layer "F.SilkS")
			(hide yes)
			(effects
				(font
					(size 1.27 1.27)
				)
			)
		)
		(property "Value" ""
			(at 0 0 270)
			(layer "F.Fab")
			(effects
				(font
					(size 1.27 1.27)
				)
			)
		)
		(duplicate_pad_numbers_are_jumpers no)
		(fp_line
			(start -0.7874 0.4064)
			(end -0.7874 -0.4064)
			(stroke
				(width 0.1524)
				(type default)
			)
			(layer "F.SilkS")
		)
		(fp_line
			(start 0.7874 0.4064)
			(end -0.7874 0.4064)
			(stroke
				(width 0.1524)
				(type default)
			)
			(layer "F.SilkS")
		)
		(fp_line
			(start -0.7874 -0.4064)
			(end 0.7874 -0.4064)
			(stroke
				(width 0.1524)
				(type default)
			)
			(layer "F.SilkS")
		)
		(fp_line
			(start 0.7874 -0.4064)
			(end 0.7874 0.4064)
			(stroke
				(width 0.1524)
				(type default)
			)
			(layer "F.SilkS")
		)
		(fp_line
			(start -0.67945 0.3048)
			(end -0.67945 -0.305054)
			(stroke
				(width 0.1)
				(type default)
			)
			(layer "F.Fab")
		)
		(fp_line
			(start -0.12065 0.3048)
			(end -0.67945 0.3048)
			(stroke
				(width 0.1)
				(type default)
			)
			(layer "F.Fab")
		)
		(fp_line
			(start 0.120396 0.3048)
			(end 0.120396 0.2794)
			(stroke
				(width 0.1)
				(type default)
			)
			(layer "F.Fab")
		)
		(fp_line
			(start 0.67945 0.3048)
			(end 0.120396 0.3048)
			(stroke
				(width 0.1)
				(type default)
			)
			(layer "F.Fab")
		)
		(fp_line
			(start -0.12065 0.2794)
			(end -0.12065 0.3048)
			(stroke
				(width 0.1)
				(type default)
			)
			(layer "F.Fab")
		)
		(fp_line
			(start 0.120396 0.2794)
			(end -0.12065 0.2794)
			(stroke
				(width 0.1)
				(type default)
			)
			(layer "F.Fab")
		)
		(fp_line
			(start -0.12065 -0.2794)
			(end 0.12065 -0.2794)
			(stroke
				(width 0.1)
				(type default)
			)
			(layer "F.Fab")
		)
		(fp_line
			(start 0.12065 -0.2794)
			(end 0.12065 -0.3048)
			(stroke
				(width 0.1)
				(type default)
			)
			(layer "F.Fab")
		)
		(fp_line
			(start 0.12065 -0.3048)
			(end 0.67945 -0.3048)
			(stroke
				(width 0.1)
				(type default)
			)
			(layer "F.Fab")
		)
		(fp_line
			(start 0.67945 -0.3048)
			(end 0.67945 0.3048)
			(stroke
				(width 0.1)
				(type default)
			)
			(layer "F.Fab")
		)
		(fp_line
			(start -0.67945 -0.305054)
			(end -0.12065 -0.305054)
			(stroke
				(width 0.1)
				(type default)
			)
			(layer "F.Fab")
		)
		(fp_line
			(start -0.12065 -0.305054)
			(end -0.12065 -0.2794)
			(stroke
				(width 0.1)
				(type default)
			)
			(layer "F.Fab")
		)
		(pad "1" smd circle
			(at -0.40005 0 270)
			(size 0 0)
			(layers "F.Cu" "F.Mask" "F.Paste")
			(net "PVDDCR_CPU1_P0_PVCC")
		)
		(pad "2" smd circle
			(at 0.40005 0 270)
			(size 0 0)
			(layers "F.Cu" "F.Mask" "F.Paste")
			(net "GND")
		)
	)
	(footprint ""
		(layer "F.Cu")
		(at 313.8297 -409.104592)
		(property "Reference" "C7032"
			(at -5.4864 3.171952 0)
			(unlocked yes)
			(layer "F.SilkS")
			(effects
				(font
					(size 0.7874 0.5842)
					(thickness 0.1524)
				)
				(justify left)
			)
		)
		(property "Value" ""
			(at 0 0 0)
			(layer "F.Fab")
			(effects
				(font
					(size 1.27 1.27)
				)
			)
		)
		(duplicate_pad_numbers_are_jumpers no)
		(fp_line
			(start -4.84378 -2.150618)
			(end -4.842256 2.163064)
			(stroke
				(width 0.1524)
				(type default)
			)
			(layer "F.SilkS")
		)
		(fp_line
			(start -4.84378 -2.150618)
			(end -4.53898 -2.150618)
			(stroke
				(width 0.1524)
				(type default)
			)
			(layer "F.SilkS")
		)
		(fp_line
			(start -4.83108 2.150364)
			(end -4.447794 2.149348)
			(stroke
				(width 0.1524)
				(type default)
			)
			(layer "F.SilkS")
		)
		(fp_line
			(start -4.69138 -2.150618)
			(end -4.692396 2.161032)
			(stroke
				(width 0.1524)
				(type default)
			)
			(layer "F.SilkS")
		)
		(fp_line
			(start -4.53898 -2.150618)
			(end -4.539742 2.152142)
			(stroke
				(width 0.1524)
				(type default)
			)
			(layer "F.SilkS")
		)
		(fp_line
			(start -4.53898 -2.15011)
			(end 4.53898 -2.15011)
			(stroke
				(width 0.1524)
				(type default)
			)
			(layer "F.SilkS")
		)
		(fp_line
			(start -4.53898 2.15011)
			(end -4.53898 -2.15011)
			(stroke
				(width 0.1524)
				(type default)
			)
			(layer "F.SilkS")
		)
		(fp_line
			(start 4.53898 -2.15011)
			(end 4.53898 2.15011)
			(stroke
				(width 0.1524)
				(type default)
			)
			(layer "F.SilkS")
		)
		(fp_line
			(start 4.53898 2.15011)
			(end -4.53898 2.15011)
			(stroke
				(width 0.1524)
				(type default)
			)
			(layer "F.SilkS")
		)
		(fp_line
			(start -3.64998 -2.15011)
			(end 3.64998 -2.15011)
			(stroke
				(width 0.1)
				(type default)
			)
			(layer "F.Fab")
		)
		(fp_line
			(start -3.64998 2.15011)
			(end -3.64998 -2.15011)
			(stroke
				(width 0.1)
				(type default)
			)
			(layer "F.Fab")
		)
		(fp_line
			(start 3.64998 -2.15011)
			(end 3.64998 2.15011)
			(stroke
				(width 0.1)
				(type default)
			)
			(layer "F.Fab")
		)
		(fp_line
			(start 3.64998 2.15011)
			(end -3.64998 2.15011)
			(stroke
				(width 0.1)
				(type default)
			)
			(layer "F.Fab")
		)
		(fp_text user "+"
			(at -6.161532 0.996442 0)
			(unlocked yes)
			(layer "F.SilkS")
			(effects
				(font
					(size 1.905 1.4224)
					(thickness 0.1524)
				)
				(justify left)
			)
		)
		(fp_text user "-"
			(at 6.662166 -2.306828 180)
			(unlocked yes)
			(layer "F.SilkS")
			(effects
				(font
					(size 1.905 1.4224)
					(thickness 0.1524)
				)
				(justify left)
			)
		)
		(fp_text user "+"
			(at -6.214872 -0.337058 0)
			(unlocked yes)
			(layer "F.Fab")
			(effects
				(font
					(size 1.905 1.4224)
					(thickness 0.1524)
				)
				(justify left)
			)
		)
		(fp_text user "-"
			(at 4.313174 -0.094488 0)
			(unlocked yes)
			(layer "F.Fab")
			(effects
				(font
					(size 1.905 1.4224)
					(thickness 0.1524)
				)
				(justify left)
			)
		)
		(pad "1" smd rect
			(at -3.199892 0)
			(size 2.413 2.8194)
			(layers "F.Cu" "F.Mask" "F.Paste")
			(net "P0V9_CPU0_RT_2D")
		)
		(pad "2" smd rect
			(at 3.199892 0)
			(size 2.413 2.8194)
			(layers "F.Cu" "F.Mask" "F.Paste")
			(net "GND")
		)
	)
)
